FILE_TYPE=LIBRARY_PARTS;
primitive 'SCONN288_H44441003','SCONN288_H44441003_PIP';
  pin
    '12V'<1>:
      PIN_NUMBER='(0,0,0,1)';
      PINUSE='POWER';
      NO_LOAD_CHECK='Both';
      NO_IO_CHECK='Both';
      NO_ASSERT_CHECK='TRUE';
      NO_DIR_CHECK='TRUE';
      ALLOW_CONNECT='TRUE';
    '12V'<0>:
      PIN_NUMBER='(0,0,0,145)';
      PINUSE='POWER';
      NO_LOAD_CHECK='Both';
      NO_IO_CHECK='Both';
      NO_ASSERT_CHECK='TRUE';
      NO_DIR_CHECK='TRUE';
      ALLOW_CONNECT='TRUE';
    'A0':
      PIN_NUMBER='(79,0,0,0)';
      BIDIRECTIONAL='TRUE';
      INPUT_LOAD='(-0.01,0.01)';
      OUTPUT_LOAD='(1.0,-1.0)';
    'A1':
      PIN_NUMBER='(72,0,0,0)';
      BIDIRECTIONAL='TRUE';
      INPUT_LOAD='(-0.01,0.01)';
      OUTPUT_LOAD='(1.0,-1.0)';
    'A10':
      PIN_NUMBER='(225,0,0,0)';
      BIDIRECTIONAL='TRUE';
      INPUT_LOAD='(-0.01,0.01)';
      OUTPUT_LOAD='(1.0,-1.0)';
    'A11':
      PIN_NUMBER='(210,0,0,0)';
      BIDIRECTIONAL='TRUE';
      INPUT_LOAD='(-0.01,0.01)';
      OUTPUT_LOAD='(1.0,-1.0)';
    'A12':
      PIN_NUMBER='(65,0,0,0)';
      BIDIRECTIONAL='TRUE';
      INPUT_LOAD='(-0.01,0.01)';
      OUTPUT_LOAD='(1.0,-1.0)';
    'A13':
      PIN_NUMBER='(232,0,0,0)';
      BIDIRECTIONAL='TRUE';
      INPUT_LOAD='(-0.01,0.01)';
      OUTPUT_LOAD='(1.0,-1.0)';
    'A14_WE_N':
      PIN_NUMBER='(228,0,0,0)';
      BIDIRECTIONAL='TRUE';
      INPUT_LOAD='(-0.01,0.01)';
      OUTPUT_LOAD='(1.0,-1.0)';
    'A15_CAS_N':
      PIN_NUMBER='(86,0,0,0)';
      BIDIRECTIONAL='TRUE';
      INPUT_LOAD='(-0.01,0.01)';
      OUTPUT_LOAD='(1.0,-1.0)';
    'A16_RAS_N':
      PIN_NUMBER='(82,0,0,0)';
      BIDIRECTIONAL='TRUE';
      INPUT_LOAD='(-0.01,0.01)';
      OUTPUT_LOAD='(1.0,-1.0)';
    'A17':
      PIN_NUMBER='(234,0,0,0)';
      BIDIRECTIONAL='TRUE';
      INPUT_LOAD='(-0.01,0.01)';
      OUTPUT_LOAD='(1.0,-1.0)';
    'A2':
      PIN_NUMBER='(216,0,0,0)';
      BIDIRECTIONAL='TRUE';
      INPUT_LOAD='(-0.01,0.01)';
      OUTPUT_LOAD='(1.0,-1.0)';
    'A3':
      PIN_NUMBER='(71,0,0,0)';
      BIDIRECTIONAL='TRUE';
      INPUT_LOAD='(-0.01,0.01)';
      OUTPUT_LOAD='(1.0,-1.0)';
    'A4':
      PIN_NUMBER='(214,0,0,0)';
      BIDIRECTIONAL='TRUE';
      INPUT_LOAD='(-0.01,0.01)';
      OUTPUT_LOAD='(1.0,-1.0)';
    'A5':
      PIN_NUMBER='(213,0,0,0)';
      BIDIRECTIONAL='TRUE';
      INPUT_LOAD='(-0.01,0.01)';
      OUTPUT_LOAD='(1.0,-1.0)';
    'A6':
      PIN_NUMBER='(69,0,0,0)';
      BIDIRECTIONAL='TRUE';
      INPUT_LOAD='(-0.01,0.01)';
      OUTPUT_LOAD='(1.0,-1.0)';
    'A7':
      PIN_NUMBER='(211,0,0,0)';
      BIDIRECTIONAL='TRUE';
      INPUT_LOAD='(-0.01,0.01)';
      OUTPUT_LOAD='(1.0,-1.0)';
    'A8':
      PIN_NUMBER='(68,0,0,0)';
      BIDIRECTIONAL='TRUE';
      INPUT_LOAD='(-0.01,0.01)';
      OUTPUT_LOAD='(1.0,-1.0)';
    'A9':
      PIN_NUMBER='(66,0,0,0)';
      BIDIRECTIONAL='TRUE';
      INPUT_LOAD='(-0.01,0.01)';
      OUTPUT_LOAD='(1.0,-1.0)';
    'ACT_N':
      PIN_NUMBER='(62,0,0,0)';
      BIDIRECTIONAL='TRUE';
      INPUT_LOAD='(-0.01,0.01)';
      OUTPUT_LOAD='(1.0,-1.0)';
    'ALERT_N':
      PIN_NUMBER='(208,0,0,0)';
      BIDIRECTIONAL='TRUE';
      INPUT_LOAD='(-0.01,0.01)';
      OUTPUT_LOAD='(1.0,-1.0)';
    'BA'<1>:
      PIN_NUMBER='(224,0,0,0)';
      BIDIRECTIONAL='TRUE';
      INPUT_LOAD='(-0.01,0.01)';
      OUTPUT_LOAD='(1.0,-1.0)';
    'BA'<0>:
      PIN_NUMBER='(81,0,0,0)';
      BIDIRECTIONAL='TRUE';
      INPUT_LOAD='(-0.01,0.01)';
      OUTPUT_LOAD='(1.0,-1.0)';
    'BG'<1>:
      PIN_NUMBER='(207,0,0,0)';
      BIDIRECTIONAL='TRUE';
      INPUT_LOAD='(-0.01,0.01)';
      OUTPUT_LOAD='(1.0,-1.0)';
    'BG'<0>:
      PIN_NUMBER='(63,0,0,0)';
      BIDIRECTIONAL='TRUE';
      INPUT_LOAD='(-0.01,0.01)';
      OUTPUT_LOAD='(1.0,-1.0)';
    'C'<2>:
      PIN_NUMBER='(235,0,0,0)';
      BIDIRECTIONAL='TRUE';
      INPUT_LOAD='(-0.01,0.01)';
      OUTPUT_LOAD='(1.0,-1.0)';
    'CB'<7>:
      PIN_NUMBER='(199,0,0,0)';
      BIDIRECTIONAL='TRUE';
      INPUT_LOAD='(-0.01,0.01)';
      OUTPUT_LOAD='(1.0,-1.0)';
    'CB'<6>:
      PIN_NUMBER='(54,0,0,0)';
      BIDIRECTIONAL='TRUE';
      INPUT_LOAD='(-0.01,0.01)';
      OUTPUT_LOAD='(1.0,-1.0)';
    'CB'<5>:
      PIN_NUMBER='(192,0,0,0)';
      BIDIRECTIONAL='TRUE';
      INPUT_LOAD='(-0.01,0.01)';
      OUTPUT_LOAD='(1.0,-1.0)';
    'CB'<4>:
      PIN_NUMBER='(47,0,0,0)';
      BIDIRECTIONAL='TRUE';
      INPUT_LOAD='(-0.01,0.01)';
      OUTPUT_LOAD='(1.0,-1.0)';
    'CB'<3>:
      PIN_NUMBER='(201,0,0,0)';
      BIDIRECTIONAL='TRUE';
      INPUT_LOAD='(-0.01,0.01)';
      OUTPUT_LOAD='(1.0,-1.0)';
    'CB'<2>:
      PIN_NUMBER='(56,0,0,0)';
      BIDIRECTIONAL='TRUE';
      INPUT_LOAD='(-0.01,0.01)';
      OUTPUT_LOAD='(1.0,-1.0)';
    'CB'<1>:
      PIN_NUMBER='(194,0,0,0)';
      BIDIRECTIONAL='TRUE';
      INPUT_LOAD='(-0.01,0.01)';
      OUTPUT_LOAD='(1.0,-1.0)';
    'CB'<0>:
      PIN_NUMBER='(49,0,0,0)';
      BIDIRECTIONAL='TRUE';
      INPUT_LOAD='(-0.01,0.01)';
      OUTPUT_LOAD='(1.0,-1.0)';
    'CK0N':
      PIN_NUMBER='(75,0,0,0)';
      BIDIRECTIONAL='TRUE';
      INPUT_LOAD='(-0.01,0.01)';
      OUTPUT_LOAD='(1.0,-1.0)';
    'CK0P':
      PIN_NUMBER='(74,0,0,0)';
      BIDIRECTIONAL='TRUE';
      INPUT_LOAD='(-0.01,0.01)';
      OUTPUT_LOAD='(1.0,-1.0)';
    'CK1N':
      PIN_NUMBER='(219,0,0,0)';
      BIDIRECTIONAL='TRUE';
      INPUT_LOAD='(-0.01,0.01)';
      OUTPUT_LOAD='(1.0,-1.0)';
    'CK1P':
      PIN_NUMBER='(218,0,0,0)';
      BIDIRECTIONAL='TRUE';
      INPUT_LOAD='(-0.01,0.01)';
      OUTPUT_LOAD='(1.0,-1.0)';
    'CKE'<1>:
      PIN_NUMBER='(203,0,0,0)';
      BIDIRECTIONAL='TRUE';
      INPUT_LOAD='(-0.01,0.01)';
      OUTPUT_LOAD='(1.0,-1.0)';
    'CKE'<0>:
      PIN_NUMBER='(60,0,0,0)';
      BIDIRECTIONAL='TRUE';
      INPUT_LOAD='(-0.01,0.01)';
      OUTPUT_LOAD='(1.0,-1.0)';
    'DQ'<63>:
      PIN_NUMBER='(280,0,0,0)';
      BIDIRECTIONAL='TRUE';
      INPUT_LOAD='(-0.01,0.01)';
      OUTPUT_LOAD='(1.0,-1.0)';
    'DQ'<62>:
      PIN_NUMBER='(135,0,0,0)';
      BIDIRECTIONAL='TRUE';
      INPUT_LOAD='(-0.01,0.01)';
      OUTPUT_LOAD='(1.0,-1.0)';
    'DQ'<61>:
      PIN_NUMBER='(273,0,0,0)';
      BIDIRECTIONAL='TRUE';
      INPUT_LOAD='(-0.01,0.01)';
      OUTPUT_LOAD='(1.0,-1.0)';
    'DQ'<60>:
      PIN_NUMBER='(128,0,0,0)';
      BIDIRECTIONAL='TRUE';
      INPUT_LOAD='(-0.01,0.01)';
      OUTPUT_LOAD='(1.0,-1.0)';
    'DQ'<59>:
      PIN_NUMBER='(282,0,0,0)';
      BIDIRECTIONAL='TRUE';
      INPUT_LOAD='(-0.01,0.01)';
      OUTPUT_LOAD='(1.0,-1.0)';
    'DQ'<58>:
      PIN_NUMBER='(137,0,0,0)';
      BIDIRECTIONAL='TRUE';
      INPUT_LOAD='(-0.01,0.01)';
      OUTPUT_LOAD='(1.0,-1.0)';
    'DQ'<57>:
      PIN_NUMBER='(275,0,0,0)';
      BIDIRECTIONAL='TRUE';
      INPUT_LOAD='(-0.01,0.01)';
      OUTPUT_LOAD='(1.0,-1.0)';
    'DQ'<56>:
      PIN_NUMBER='(130,0,0,0)';
      BIDIRECTIONAL='TRUE';
      INPUT_LOAD='(-0.01,0.01)';
      OUTPUT_LOAD='(1.0,-1.0)';
    'DQ'<55>:
      PIN_NUMBER='(269,0,0,0)';
      BIDIRECTIONAL='TRUE';
      INPUT_LOAD='(-0.01,0.01)';
      OUTPUT_LOAD='(1.0,-1.0)';
    'DQ'<54>:
      PIN_NUMBER='(124,0,0,0)';
      BIDIRECTIONAL='TRUE';
      INPUT_LOAD='(-0.01,0.01)';
      OUTPUT_LOAD='(1.0,-1.0)';
    'DQ'<53>:
      PIN_NUMBER='(262,0,0,0)';
      BIDIRECTIONAL='TRUE';
      INPUT_LOAD='(-0.01,0.01)';
      OUTPUT_LOAD='(1.0,-1.0)';
    'DQ'<52>:
      PIN_NUMBER='(117,0,0,0)';
      BIDIRECTIONAL='TRUE';
      INPUT_LOAD='(-0.01,0.01)';
      OUTPUT_LOAD='(1.0,-1.0)';
    'DQ'<51>:
      PIN_NUMBER='(271,0,0,0)';
      BIDIRECTIONAL='TRUE';
      INPUT_LOAD='(-0.01,0.01)';
      OUTPUT_LOAD='(1.0,-1.0)';
    'DQ'<50>:
      PIN_NUMBER='(126,0,0,0)';
      BIDIRECTIONAL='TRUE';
      INPUT_LOAD='(-0.01,0.01)';
      OUTPUT_LOAD='(1.0,-1.0)';
    'DQ'<49>:
      PIN_NUMBER='(264,0,0,0)';
      BIDIRECTIONAL='TRUE';
      INPUT_LOAD='(-0.01,0.01)';
      OUTPUT_LOAD='(1.0,-1.0)';
    'DQ'<48>:
      PIN_NUMBER='(119,0,0,0)';
      BIDIRECTIONAL='TRUE';
      INPUT_LOAD='(-0.01,0.01)';
      OUTPUT_LOAD='(1.0,-1.0)';
    'DQ'<47>:
      PIN_NUMBER='(258,0,0,0)';
      BIDIRECTIONAL='TRUE';
      INPUT_LOAD='(-0.01,0.01)';
      OUTPUT_LOAD='(1.0,-1.0)';
    'DQ'<46>:
      PIN_NUMBER='(113,0,0,0)';
      BIDIRECTIONAL='TRUE';
      INPUT_LOAD='(-0.01,0.01)';
      OUTPUT_LOAD='(1.0,-1.0)';
    'DQ'<45>:
      PIN_NUMBER='(251,0,0,0)';
      BIDIRECTIONAL='TRUE';
      INPUT_LOAD='(-0.01,0.01)';
      OUTPUT_LOAD='(1.0,-1.0)';
    'DQ'<44>:
      PIN_NUMBER='(106,0,0,0)';
      BIDIRECTIONAL='TRUE';
      INPUT_LOAD='(-0.01,0.01)';
      OUTPUT_LOAD='(1.0,-1.0)';
    'DQ'<43>:
      PIN_NUMBER='(260,0,0,0)';
      BIDIRECTIONAL='TRUE';
      INPUT_LOAD='(-0.01,0.01)';
      OUTPUT_LOAD='(1.0,-1.0)';
    'DQ'<42>:
      PIN_NUMBER='(115,0,0,0)';
      BIDIRECTIONAL='TRUE';
      INPUT_LOAD='(-0.01,0.01)';
      OUTPUT_LOAD='(1.0,-1.0)';
    'DQ'<41>:
      PIN_NUMBER='(253,0,0,0)';
      BIDIRECTIONAL='TRUE';
      INPUT_LOAD='(-0.01,0.01)';
      OUTPUT_LOAD='(1.0,-1.0)';
    'DQ'<40>:
      PIN_NUMBER='(108,0,0,0)';
      BIDIRECTIONAL='TRUE';
      INPUT_LOAD='(-0.01,0.01)';
      OUTPUT_LOAD='(1.0,-1.0)';
    'DQ'<39>:
      PIN_NUMBER='(247,0,0,0)';
      BIDIRECTIONAL='TRUE';
      INPUT_LOAD='(-0.01,0.01)';
      OUTPUT_LOAD='(1.0,-1.0)';
    'DQ'<38>:
      PIN_NUMBER='(102,0,0,0)';
      BIDIRECTIONAL='TRUE';
      INPUT_LOAD='(-0.01,0.01)';
      OUTPUT_LOAD='(1.0,-1.0)';
    'DQ'<37>:
      PIN_NUMBER='(240,0,0,0)';
      BIDIRECTIONAL='TRUE';
      INPUT_LOAD='(-0.01,0.01)';
      OUTPUT_LOAD='(1.0,-1.0)';
    'DQ'<36>:
      PIN_NUMBER='(95,0,0,0)';
      BIDIRECTIONAL='TRUE';
      INPUT_LOAD='(-0.01,0.01)';
      OUTPUT_LOAD='(1.0,-1.0)';
    'DQ'<35>:
      PIN_NUMBER='(249,0,0,0)';
      BIDIRECTIONAL='TRUE';
      INPUT_LOAD='(-0.01,0.01)';
      OUTPUT_LOAD='(1.0,-1.0)';
    'DQ'<34>:
      PIN_NUMBER='(104,0,0,0)';
      BIDIRECTIONAL='TRUE';
      INPUT_LOAD='(-0.01,0.01)';
      OUTPUT_LOAD='(1.0,-1.0)';
    'DQ'<33>:
      PIN_NUMBER='(242,0,0,0)';
      BIDIRECTIONAL='TRUE';
      INPUT_LOAD='(-0.01,0.01)';
      OUTPUT_LOAD='(1.0,-1.0)';
    'DQ'<32>:
      PIN_NUMBER='(97,0,0,0)';
      BIDIRECTIONAL='TRUE';
      INPUT_LOAD='(-0.01,0.01)';
      OUTPUT_LOAD='(1.0,-1.0)';
    'DQ'<31>:
      PIN_NUMBER='(188,0,0,0)';
      BIDIRECTIONAL='TRUE';
      INPUT_LOAD='(-0.01,0.01)';
      OUTPUT_LOAD='(1.0,-1.0)';
    'DQ'<30>:
      PIN_NUMBER='(43,0,0,0)';
      BIDIRECTIONAL='TRUE';
      INPUT_LOAD='(-0.01,0.01)';
      OUTPUT_LOAD='(1.0,-1.0)';
    'DQ'<29>:
      PIN_NUMBER='(181,0,0,0)';
      BIDIRECTIONAL='TRUE';
      INPUT_LOAD='(-0.01,0.01)';
      OUTPUT_LOAD='(1.0,-1.0)';
    'DQ'<28>:
      PIN_NUMBER='(36,0,0,0)';
      BIDIRECTIONAL='TRUE';
      INPUT_LOAD='(-0.01,0.01)';
      OUTPUT_LOAD='(1.0,-1.0)';
    'DQ'<27>:
      PIN_NUMBER='(190,0,0,0)';
      BIDIRECTIONAL='TRUE';
      INPUT_LOAD='(-0.01,0.01)';
      OUTPUT_LOAD='(1.0,-1.0)';
    'DQ'<26>:
      PIN_NUMBER='(45,0,0,0)';
      BIDIRECTIONAL='TRUE';
      INPUT_LOAD='(-0.01,0.01)';
      OUTPUT_LOAD='(1.0,-1.0)';
    'DQ'<25>:
      PIN_NUMBER='(183,0,0,0)';
      BIDIRECTIONAL='TRUE';
      INPUT_LOAD='(-0.01,0.01)';
      OUTPUT_LOAD='(1.0,-1.0)';
    'DQ'<24>:
      PIN_NUMBER='(38,0,0,0)';
      BIDIRECTIONAL='TRUE';
      INPUT_LOAD='(-0.01,0.01)';
      OUTPUT_LOAD='(1.0,-1.0)';
    'DQ'<23>:
      PIN_NUMBER='(177,0,0,0)';
      BIDIRECTIONAL='TRUE';
      INPUT_LOAD='(-0.01,0.01)';
      OUTPUT_LOAD='(1.0,-1.0)';
    'DQ'<22>:
      PIN_NUMBER='(32,0,0,0)';
      BIDIRECTIONAL='TRUE';
      INPUT_LOAD='(-0.01,0.01)';
      OUTPUT_LOAD='(1.0,-1.0)';
    'DQ'<21>:
      PIN_NUMBER='(170,0,0,0)';
      BIDIRECTIONAL='TRUE';
      INPUT_LOAD='(-0.01,0.01)';
      OUTPUT_LOAD='(1.0,-1.0)';
    'DQ'<20>:
      PIN_NUMBER='(25,0,0,0)';
      BIDIRECTIONAL='TRUE';
      INPUT_LOAD='(-0.01,0.01)';
      OUTPUT_LOAD='(1.0,-1.0)';
    'DQ'<19>:
      PIN_NUMBER='(179,0,0,0)';
      BIDIRECTIONAL='TRUE';
      INPUT_LOAD='(-0.01,0.01)';
      OUTPUT_LOAD='(1.0,-1.0)';
    'DQ'<18>:
      PIN_NUMBER='(34,0,0,0)';
      BIDIRECTIONAL='TRUE';
      INPUT_LOAD='(-0.01,0.01)';
      OUTPUT_LOAD='(1.0,-1.0)';
    'DQ'<17>:
      PIN_NUMBER='(172,0,0,0)';
      BIDIRECTIONAL='TRUE';
      INPUT_LOAD='(-0.01,0.01)';
      OUTPUT_LOAD='(1.0,-1.0)';
    'DQ'<16>:
      PIN_NUMBER='(27,0,0,0)';
      BIDIRECTIONAL='TRUE';
      INPUT_LOAD='(-0.01,0.01)';
      OUTPUT_LOAD='(1.0,-1.0)';
    'DQ'<15>:
      PIN_NUMBER='(166,0,0,0)';
      BIDIRECTIONAL='TRUE';
      INPUT_LOAD='(-0.01,0.01)';
      OUTPUT_LOAD='(1.0,-1.0)';
    'DQ'<14>:
      PIN_NUMBER='(21,0,0,0)';
      BIDIRECTIONAL='TRUE';
      INPUT_LOAD='(-0.01,0.01)';
      OUTPUT_LOAD='(1.0,-1.0)';
    'DQ'<13>:
      PIN_NUMBER='(159,0,0,0)';
      BIDIRECTIONAL='TRUE';
      INPUT_LOAD='(-0.01,0.01)';
      OUTPUT_LOAD='(1.0,-1.0)';
    'DQ'<12>:
      PIN_NUMBER='(14,0,0,0)';
      BIDIRECTIONAL='TRUE';
      INPUT_LOAD='(-0.01,0.01)';
      OUTPUT_LOAD='(1.0,-1.0)';
    'DQ'<11>:
      PIN_NUMBER='(168,0,0,0)';
      BIDIRECTIONAL='TRUE';
      INPUT_LOAD='(-0.01,0.01)';
      OUTPUT_LOAD='(1.0,-1.0)';
    'DQ'<10>:
      PIN_NUMBER='(23,0,0,0)';
      BIDIRECTIONAL='TRUE';
      INPUT_LOAD='(-0.01,0.01)';
      OUTPUT_LOAD='(1.0,-1.0)';
    'DQ'<9>:
      PIN_NUMBER='(161,0,0,0)';
      BIDIRECTIONAL='TRUE';
      INPUT_LOAD='(-0.01,0.01)';
      OUTPUT_LOAD='(1.0,-1.0)';
    'DQ'<8>:
      PIN_NUMBER='(16,0,0,0)';
      BIDIRECTIONAL='TRUE';
      INPUT_LOAD='(-0.01,0.01)';
      OUTPUT_LOAD='(1.0,-1.0)';
    'DQ'<7>:
      PIN_NUMBER='(155,0,0,0)';
      BIDIRECTIONAL='TRUE';
      INPUT_LOAD='(-0.01,0.01)';
      OUTPUT_LOAD='(1.0,-1.0)';
    'DQ'<6>:
      PIN_NUMBER='(10,0,0,0)';
      BIDIRECTIONAL='TRUE';
      INPUT_LOAD='(-0.01,0.01)';
      OUTPUT_LOAD='(1.0,-1.0)';
    'DQ'<5>:
      PIN_NUMBER='(148,0,0,0)';
      BIDIRECTIONAL='TRUE';
      INPUT_LOAD='(-0.01,0.01)';
      OUTPUT_LOAD='(1.0,-1.0)';
    'DQ'<4>:
      PIN_NUMBER='(3,0,0,0)';
      BIDIRECTIONAL='TRUE';
      INPUT_LOAD='(-0.01,0.01)';
      OUTPUT_LOAD='(1.0,-1.0)';
    'DQ'<3>:
      PIN_NUMBER='(157,0,0,0)';
      BIDIRECTIONAL='TRUE';
      INPUT_LOAD='(-0.01,0.01)';
      OUTPUT_LOAD='(1.0,-1.0)';
    'DQ'<2>:
      PIN_NUMBER='(12,0,0,0)';
      BIDIRECTIONAL='TRUE';
      INPUT_LOAD='(-0.01,0.01)';
      OUTPUT_LOAD='(1.0,-1.0)';
    'DQ'<1>:
      PIN_NUMBER='(150,0,0,0)';
      BIDIRECTIONAL='TRUE';
      INPUT_LOAD='(-0.01,0.01)';
      OUTPUT_LOAD='(1.0,-1.0)';
    'DQ'<0>:
      PIN_NUMBER='(5,0,0,0)';
      BIDIRECTIONAL='TRUE';
      INPUT_LOAD='(-0.01,0.01)';
      OUTPUT_LOAD='(1.0,-1.0)';
    'DQS0N':
      PIN_NUMBER='(0,152,0,0)';
      BIDIRECTIONAL='TRUE';
      INPUT_LOAD='(-0.01,0.01)';
      OUTPUT_LOAD='(1.0,-1.0)';
    'DQS0P':
      PIN_NUMBER='(0,153,0,0)';
      BIDIRECTIONAL='TRUE';
      INPUT_LOAD='(-0.01,0.01)';
      OUTPUT_LOAD='(1.0,-1.0)';
    'DQS10N':
      PIN_NUMBER='(0,19,0,0)';
      BIDIRECTIONAL='TRUE';
      INPUT_LOAD='(-0.01,0.01)';
      OUTPUT_LOAD='(1.0,-1.0)';
    'DQS10P':
      PIN_NUMBER='(0,18,0,0)';
      BIDIRECTIONAL='TRUE';
      INPUT_LOAD='(-0.01,0.01)';
      OUTPUT_LOAD='(1.0,-1.0)';
    'DQS11N':
      PIN_NUMBER='(0,30,0,0)';
      BIDIRECTIONAL='TRUE';
      INPUT_LOAD='(-0.01,0.01)';
      OUTPUT_LOAD='(1.0,-1.0)';
    'DQS11P':
      PIN_NUMBER='(0,29,0,0)';
      BIDIRECTIONAL='TRUE';
      INPUT_LOAD='(-0.01,0.01)';
      OUTPUT_LOAD='(1.0,-1.0)';
    'DQS12N':
      PIN_NUMBER='(0,41,0,0)';
      BIDIRECTIONAL='TRUE';
      INPUT_LOAD='(-0.01,0.01)';
      OUTPUT_LOAD='(1.0,-1.0)';
    'DQS12P':
      PIN_NUMBER='(0,40,0,0)';
      BIDIRECTIONAL='TRUE';
      INPUT_LOAD='(-0.01,0.01)';
      OUTPUT_LOAD='(1.0,-1.0)';
    'DQS13N':
      PIN_NUMBER='(0,100,0,0)';
      BIDIRECTIONAL='TRUE';
      INPUT_LOAD='(-0.01,0.01)';
      OUTPUT_LOAD='(1.0,-1.0)';
    'DQS13P':
      PIN_NUMBER='(0,99,0,0)';
      BIDIRECTIONAL='TRUE';
      INPUT_LOAD='(-0.01,0.01)';
      OUTPUT_LOAD='(1.0,-1.0)';
    'DQS14N':
      PIN_NUMBER='(0,111,0,0)';
      BIDIRECTIONAL='TRUE';
      INPUT_LOAD='(-0.01,0.01)';
      OUTPUT_LOAD='(1.0,-1.0)';
    'DQS14P':
      PIN_NUMBER='(0,110,0,0)';
      BIDIRECTIONAL='TRUE';
      INPUT_LOAD='(-0.01,0.01)';
      OUTPUT_LOAD='(1.0,-1.0)';
    'DQS15N':
      PIN_NUMBER='(0,122,0,0)';
      BIDIRECTIONAL='TRUE';
      INPUT_LOAD='(-0.01,0.01)';
      OUTPUT_LOAD='(1.0,-1.0)';
    'DQS15P':
      PIN_NUMBER='(0,121,0,0)';
      BIDIRECTIONAL='TRUE';
      INPUT_LOAD='(-0.01,0.01)';
      OUTPUT_LOAD='(1.0,-1.0)';
    'DQS16N':
      PIN_NUMBER='(0,133,0,0)';
      BIDIRECTIONAL='TRUE';
      INPUT_LOAD='(-0.01,0.01)';
      OUTPUT_LOAD='(1.0,-1.0)';
    'DQS16P':
      PIN_NUMBER='(0,132,0,0)';
      BIDIRECTIONAL='TRUE';
      INPUT_LOAD='(-0.01,0.01)';
      OUTPUT_LOAD='(1.0,-1.0)';
    'DQS17N':
      PIN_NUMBER='(0,52,0,0)';
      BIDIRECTIONAL='TRUE';
      INPUT_LOAD='(-0.01,0.01)';
      OUTPUT_LOAD='(1.0,-1.0)';
    'DQS17P':
      PIN_NUMBER='(0,51,0,0)';
      BIDIRECTIONAL='TRUE';
      INPUT_LOAD='(-0.01,0.01)';
      OUTPUT_LOAD='(1.0,-1.0)';
    'DQS1N':
      PIN_NUMBER='(0,163,0,0)';
      BIDIRECTIONAL='TRUE';
      INPUT_LOAD='(-0.01,0.01)';
      OUTPUT_LOAD='(1.0,-1.0)';
    'DQS1P':
      PIN_NUMBER='(0,164,0,0)';
      BIDIRECTIONAL='TRUE';
      INPUT_LOAD='(-0.01,0.01)';
      OUTPUT_LOAD='(1.0,-1.0)';
    'DQS2N':
      PIN_NUMBER='(0,174,0,0)';
      BIDIRECTIONAL='TRUE';
      INPUT_LOAD='(-0.01,0.01)';
      OUTPUT_LOAD='(1.0,-1.0)';
    'DQS2P':
      PIN_NUMBER='(0,175,0,0)';
      BIDIRECTIONAL='TRUE';
      INPUT_LOAD='(-0.01,0.01)';
      OUTPUT_LOAD='(1.0,-1.0)';
    'DQS3N':
      PIN_NUMBER='(0,185,0,0)';
      BIDIRECTIONAL='TRUE';
      INPUT_LOAD='(-0.01,0.01)';
      OUTPUT_LOAD='(1.0,-1.0)';
    'DQS3P':
      PIN_NUMBER='(0,186,0,0)';
      BIDIRECTIONAL='TRUE';
      INPUT_LOAD='(-0.01,0.01)';
      OUTPUT_LOAD='(1.0,-1.0)';
    'DQS4N':
      PIN_NUMBER='(0,244,0,0)';
      BIDIRECTIONAL='TRUE';
      INPUT_LOAD='(-0.01,0.01)';
      OUTPUT_LOAD='(1.0,-1.0)';
    'DQS4P':
      PIN_NUMBER='(0,245,0,0)';
      BIDIRECTIONAL='TRUE';
      INPUT_LOAD='(-0.01,0.01)';
      OUTPUT_LOAD='(1.0,-1.0)';
    'DQS5N':
      PIN_NUMBER='(0,255,0,0)';
      BIDIRECTIONAL='TRUE';
      INPUT_LOAD='(-0.01,0.01)';
      OUTPUT_LOAD='(1.0,-1.0)';
    'DQS5P':
      PIN_NUMBER='(0,256,0,0)';
      BIDIRECTIONAL='TRUE';
      INPUT_LOAD='(-0.01,0.01)';
      OUTPUT_LOAD='(1.0,-1.0)';
    'DQS6N':
      PIN_NUMBER='(0,266,0,0)';
      BIDIRECTIONAL='TRUE';
      INPUT_LOAD='(-0.01,0.01)';
      OUTPUT_LOAD='(1.0,-1.0)';
    'DQS6P':
      PIN_NUMBER='(0,267,0,0)';
      BIDIRECTIONAL='TRUE';
      INPUT_LOAD='(-0.01,0.01)';
      OUTPUT_LOAD='(1.0,-1.0)';
    'DQS7N':
      PIN_NUMBER='(0,277,0,0)';
      BIDIRECTIONAL='TRUE';
      INPUT_LOAD='(-0.01,0.01)';
      OUTPUT_LOAD='(1.0,-1.0)';
    'DQS7P':
      PIN_NUMBER='(0,278,0,0)';
      BIDIRECTIONAL='TRUE';
      INPUT_LOAD='(-0.01,0.01)';
      OUTPUT_LOAD='(1.0,-1.0)';
    'DQS8N':
      PIN_NUMBER='(0,196,0,0)';
      BIDIRECTIONAL='TRUE';
      INPUT_LOAD='(-0.01,0.01)';
      OUTPUT_LOAD='(1.0,-1.0)';
    'DQS8P':
      PIN_NUMBER='(0,197,0,0)';
      BIDIRECTIONAL='TRUE';
      INPUT_LOAD='(-0.01,0.01)';
      OUTPUT_LOAD='(1.0,-1.0)';
    'DQS9N':
      PIN_NUMBER='(0,8,0,0)';
      BIDIRECTIONAL='TRUE';
      INPUT_LOAD='(-0.01,0.01)';
      OUTPUT_LOAD='(1.0,-1.0)';
    'DQS9P':
      PIN_NUMBER='(0,7,0,0)';
      BIDIRECTIONAL='TRUE';
      INPUT_LOAD='(-0.01,0.01)';
      OUTPUT_LOAD='(1.0,-1.0)';
    'EVENT_N':
      PIN_NUMBER='(78,0,0,0)';
      BIDIRECTIONAL='TRUE';
      INPUT_LOAD='(-0.01,0.01)';
      OUTPUT_LOAD='(1.0,-1.0)';
    'ODT'<1>:
      PIN_NUMBER='(91,0,0,0)';
      BIDIRECTIONAL='TRUE';
      INPUT_LOAD='(-0.01,0.01)';
      OUTPUT_LOAD='(1.0,-1.0)';
    'ODT'<0>:
      PIN_NUMBER='(87,0,0,0)';
      BIDIRECTIONAL='TRUE';
      INPUT_LOAD='(-0.01,0.01)';
      OUTPUT_LOAD='(1.0,-1.0)';
    'PAR':
      PIN_NUMBER='(222,0,0,0)';
      BIDIRECTIONAL='TRUE';
      INPUT_LOAD='(-0.01,0.01)';
      OUTPUT_LOAD='(1.0,-1.0)';
    'RESET_N':
      PIN_NUMBER='(58,0,0,0)';
      BIDIRECTIONAL='TRUE';
      INPUT_LOAD='(-0.01,0.01)';
      OUTPUT_LOAD='(1.0,-1.0)';
    'RFU'<2>:
      PIN_NUMBER='(144,0,0,0)';
      BIDIRECTIONAL='TRUE';
      INPUT_LOAD='(-0.01,0.01)';
      OUTPUT_LOAD='(1.0,-1.0)';
    'RFU'<1>:
      PIN_NUMBER='(227,0,0,0)';
      BIDIRECTIONAL='TRUE';
      INPUT_LOAD='(-0.01,0.01)';
      OUTPUT_LOAD='(1.0,-1.0)';
    'RFU'<0>:
      PIN_NUMBER='(205,0,0,0)';
      BIDIRECTIONAL='TRUE';
      INPUT_LOAD='(-0.01,0.01)';
      OUTPUT_LOAD='(1.0,-1.0)';
    'S0_N':
      PIN_NUMBER='(84,0,0,0)';
      BIDIRECTIONAL='TRUE';
      INPUT_LOAD='(-0.01,0.01)';
      OUTPUT_LOAD='(1.0,-1.0)';
    'S1_N':
      PIN_NUMBER='(89,0,0,0)';
      BIDIRECTIONAL='TRUE';
      INPUT_LOAD='(-0.01,0.01)';
      OUTPUT_LOAD='(1.0,-1.0)';
    'S2_N_C'<0>:
      PIN_NUMBER='(93,0,0,0)';
      BIDIRECTIONAL='TRUE';
      INPUT_LOAD='(-0.01,0.01)';
      OUTPUT_LOAD='(1.0,-1.0)';
    'S3_N_C'<1>:
      PIN_NUMBER='(237,0,0,0)';
      BIDIRECTIONAL='TRUE';
      INPUT_LOAD='(-0.01,0.01)';
      OUTPUT_LOAD='(1.0,-1.0)';
    'SA'<2>:
      PIN_NUMBER='(238,0,0,0)';
      BIDIRECTIONAL='TRUE';
      INPUT_LOAD='(-0.01,0.01)';
      OUTPUT_LOAD='(1.0,-1.0)';
    'SA'<1>:
      PIN_NUMBER='(140,0,0,0)';
      BIDIRECTIONAL='TRUE';
      INPUT_LOAD='(-0.01,0.01)';
      OUTPUT_LOAD='(1.0,-1.0)';
    'SA'<0>:
      PIN_NUMBER='(139,0,0,0)';
      BIDIRECTIONAL='TRUE';
      INPUT_LOAD='(-0.01,0.01)';
      OUTPUT_LOAD='(1.0,-1.0)';
    'SAVE_N_NC':
      PIN_NUMBER='(230,0,0,0)';
      BIDIRECTIONAL='TRUE';
      INPUT_LOAD='(-0.01,0.01)';
      OUTPUT_LOAD='(1.0,-1.0)';
    'SCL':
      PIN_NUMBER='(141,0,0,0)';
      BIDIRECTIONAL='TRUE';
      INPUT_LOAD='(-0.01,0.01)';
      OUTPUT_LOAD='(1.0,-1.0)';
    'SDA':
      PIN_NUMBER='(285,0,0,0)';
      BIDIRECTIONAL='TRUE';
      INPUT_LOAD='(-0.01,0.01)';
      OUTPUT_LOAD='(1.0,-1.0)';
    'VDD'<25>:
      PIN_NUMBER='(0,0,0,59)';
      PINUSE='POWER';
      NO_LOAD_CHECK='Both';
      NO_IO_CHECK='Both';
      NO_ASSERT_CHECK='TRUE';
      NO_DIR_CHECK='TRUE';
      ALLOW_CONNECT='TRUE';
    'VDD'<24>:
      PIN_NUMBER='(0,0,0,61)';
      PINUSE='POWER';
      NO_LOAD_CHECK='Both';
      NO_IO_CHECK='Both';
      NO_ASSERT_CHECK='TRUE';
      NO_DIR_CHECK='TRUE';
      ALLOW_CONNECT='TRUE';
    'VDD'<23>:
      PIN_NUMBER='(0,0,0,64)';
      PINUSE='POWER';
      NO_LOAD_CHECK='Both';
      NO_IO_CHECK='Both';
      NO_ASSERT_CHECK='TRUE';
      NO_DIR_CHECK='TRUE';
      ALLOW_CONNECT='TRUE';
    'VDD'<22>:
      PIN_NUMBER='(0,0,0,67)';
      PINUSE='POWER';
      NO_LOAD_CHECK='Both';
      NO_IO_CHECK='Both';
      NO_ASSERT_CHECK='TRUE';
      NO_DIR_CHECK='TRUE';
      ALLOW_CONNECT='TRUE';
    'VDD'<21>:
      PIN_NUMBER='(0,0,0,70)';
      PINUSE='POWER';
      NO_LOAD_CHECK='Both';
      NO_IO_CHECK='Both';
      NO_ASSERT_CHECK='TRUE';
      NO_DIR_CHECK='TRUE';
      ALLOW_CONNECT='TRUE';
    'VDD'<20>:
      PIN_NUMBER='(0,0,0,73)';
      PINUSE='POWER';
      NO_LOAD_CHECK='Both';
      NO_IO_CHECK='Both';
      NO_ASSERT_CHECK='TRUE';
      NO_DIR_CHECK='TRUE';
      ALLOW_CONNECT='TRUE';
    'VDD'<19>:
      PIN_NUMBER='(0,0,0,76)';
      PINUSE='POWER';
      NO_LOAD_CHECK='Both';
      NO_IO_CHECK='Both';
      NO_ASSERT_CHECK='TRUE';
      NO_DIR_CHECK='TRUE';
      ALLOW_CONNECT='TRUE';
    'VDD'<18>:
      PIN_NUMBER='(0,0,0,80)';
      PINUSE='POWER';
      NO_LOAD_CHECK='Both';
      NO_IO_CHECK='Both';
      NO_ASSERT_CHECK='TRUE';
      NO_DIR_CHECK='TRUE';
      ALLOW_CONNECT='TRUE';
    'VDD'<17>:
      PIN_NUMBER='(0,0,0,83)';
      PINUSE='POWER';
      NO_LOAD_CHECK='Both';
      NO_IO_CHECK='Both';
      NO_ASSERT_CHECK='TRUE';
      NO_DIR_CHECK='TRUE';
      ALLOW_CONNECT='TRUE';
    'VDD'<16>:
      PIN_NUMBER='(0,0,0,85)';
      PINUSE='POWER';
      NO_LOAD_CHECK='Both';
      NO_IO_CHECK='Both';
      NO_ASSERT_CHECK='TRUE';
      NO_DIR_CHECK='TRUE';
      ALLOW_CONNECT='TRUE';
    'VDD'<15>:
      PIN_NUMBER='(0,0,0,88)';
      PINUSE='POWER';
      NO_LOAD_CHECK='Both';
      NO_IO_CHECK='Both';
      NO_ASSERT_CHECK='TRUE';
      NO_DIR_CHECK='TRUE';
      ALLOW_CONNECT='TRUE';
    'VDD'<14>:
      PIN_NUMBER='(0,0,0,90)';
      PINUSE='POWER';
      NO_LOAD_CHECK='Both';
      NO_IO_CHECK='Both';
      NO_ASSERT_CHECK='TRUE';
      NO_DIR_CHECK='TRUE';
      ALLOW_CONNECT='TRUE';
    'VDD'<13>:
      PIN_NUMBER='(0,0,0,92)';
      PINUSE='POWER';
      NO_LOAD_CHECK='Both';
      NO_IO_CHECK='Both';
      NO_ASSERT_CHECK='TRUE';
      NO_DIR_CHECK='TRUE';
      ALLOW_CONNECT='TRUE';
    'VDD'<12>:
      PIN_NUMBER='(0,0,0,204)';
      PINUSE='POWER';
      NO_LOAD_CHECK='Both';
      NO_IO_CHECK='Both';
      NO_ASSERT_CHECK='TRUE';
      NO_DIR_CHECK='TRUE';
      ALLOW_CONNECT='TRUE';
    'VDD'<11>:
      PIN_NUMBER='(0,0,0,206)';
      PINUSE='POWER';
      NO_LOAD_CHECK='Both';
      NO_IO_CHECK='Both';
      NO_ASSERT_CHECK='TRUE';
      NO_DIR_CHECK='TRUE';
      ALLOW_CONNECT='TRUE';
    'VDD'<10>:
      PIN_NUMBER='(0,0,0,209)';
      PINUSE='POWER';
      NO_LOAD_CHECK='Both';
      NO_IO_CHECK='Both';
      NO_ASSERT_CHECK='TRUE';
      NO_DIR_CHECK='TRUE';
      ALLOW_CONNECT='TRUE';
    'VDD'<9>:
      PIN_NUMBER='(0,0,0,212)';
      PINUSE='POWER';
      NO_LOAD_CHECK='Both';
      NO_IO_CHECK='Both';
      NO_ASSERT_CHECK='TRUE';
      NO_DIR_CHECK='TRUE';
      ALLOW_CONNECT='TRUE';
    'VDD'<8>:
      PIN_NUMBER='(0,0,0,215)';
      PINUSE='POWER';
      NO_LOAD_CHECK='Both';
      NO_IO_CHECK='Both';
      NO_ASSERT_CHECK='TRUE';
      NO_DIR_CHECK='TRUE';
      ALLOW_CONNECT='TRUE';
    'VDD'<7>:
      PIN_NUMBER='(0,0,0,217)';
      PINUSE='POWER';
      NO_LOAD_CHECK='Both';
      NO_IO_CHECK='Both';
      NO_ASSERT_CHECK='TRUE';
      NO_DIR_CHECK='TRUE';
      ALLOW_CONNECT='TRUE';
    'VDD'<6>:
      PIN_NUMBER='(0,0,0,220)';
      PINUSE='POWER';
      NO_LOAD_CHECK='Both';
      NO_IO_CHECK='Both';
      NO_ASSERT_CHECK='TRUE';
      NO_DIR_CHECK='TRUE';
      ALLOW_CONNECT='TRUE';
    'VDD'<5>:
      PIN_NUMBER='(0,0,0,223)';
      PINUSE='POWER';
      NO_LOAD_CHECK='Both';
      NO_IO_CHECK='Both';
      NO_ASSERT_CHECK='TRUE';
      NO_DIR_CHECK='TRUE';
      ALLOW_CONNECT='TRUE';
    'VDD'<4>:
      PIN_NUMBER='(0,0,0,226)';
      PINUSE='POWER';
      NO_LOAD_CHECK='Both';
      NO_IO_CHECK='Both';
      NO_ASSERT_CHECK='TRUE';
      NO_DIR_CHECK='TRUE';
      ALLOW_CONNECT='TRUE';
    'VDD'<3>:
      PIN_NUMBER='(0,0,0,229)';
      PINUSE='POWER';
      NO_LOAD_CHECK='Both';
      NO_IO_CHECK='Both';
      NO_ASSERT_CHECK='TRUE';
      NO_DIR_CHECK='TRUE';
      ALLOW_CONNECT='TRUE';
    'VDD'<2>:
      PIN_NUMBER='(0,0,0,231)';
      PINUSE='POWER';
      NO_LOAD_CHECK='Both';
      NO_IO_CHECK='Both';
      NO_ASSERT_CHECK='TRUE';
      NO_DIR_CHECK='TRUE';
      ALLOW_CONNECT='TRUE';
    'VDD'<1>:
      PIN_NUMBER='(0,0,0,233)';
      PINUSE='POWER';
      NO_LOAD_CHECK='Both';
      NO_IO_CHECK='Both';
      NO_ASSERT_CHECK='TRUE';
      NO_DIR_CHECK='TRUE';
      ALLOW_CONNECT='TRUE';
    'VDD'<0>:
      PIN_NUMBER='(0,0,0,236)';
      PINUSE='POWER';
      NO_LOAD_CHECK='Both';
      NO_IO_CHECK='Both';
      NO_ASSERT_CHECK='TRUE';
      NO_DIR_CHECK='TRUE';
      ALLOW_CONNECT='TRUE';
    'VDDSPD':
      PIN_NUMBER='(284,0,0,0)';
      BIDIRECTIONAL='TRUE';
      INPUT_LOAD='(-0.01,0.01)';
      OUTPUT_LOAD='(1.0,-1.0)';
    'VPP'<4>:
      PIN_NUMBER='(0,0,0,142)';
      PINUSE='POWER';
      NO_LOAD_CHECK='Both';
      NO_IO_CHECK='Both';
      NO_ASSERT_CHECK='TRUE';
      NO_DIR_CHECK='TRUE';
      ALLOW_CONNECT='TRUE';
    'VPP'<3>:
      PIN_NUMBER='(0,0,0,143)';
      PINUSE='POWER';
      NO_LOAD_CHECK='Both';
      NO_IO_CHECK='Both';
      NO_ASSERT_CHECK='TRUE';
      NO_DIR_CHECK='TRUE';
      ALLOW_CONNECT='TRUE';
    'VPP'<2>:
      PIN_NUMBER='(0,0,0,288)';
      PINUSE='POWER';
      NO_LOAD_CHECK='Both';
      NO_IO_CHECK='Both';
      NO_ASSERT_CHECK='TRUE';
      NO_DIR_CHECK='TRUE';
      ALLOW_CONNECT='TRUE';
    'VPP'<1>:
      PIN_NUMBER='(0,0,0,286)';
      PINUSE='POWER';
      NO_LOAD_CHECK='Both';
      NO_IO_CHECK='Both';
      NO_ASSERT_CHECK='TRUE';
      NO_DIR_CHECK='TRUE';
      ALLOW_CONNECT='TRUE';
    'VPP'<0>:
      PIN_NUMBER='(0,0,0,287)';
      PINUSE='POWER';
      NO_LOAD_CHECK='Both';
      NO_IO_CHECK='Both';
      NO_ASSERT_CHECK='TRUE';
      NO_DIR_CHECK='TRUE';
      ALLOW_CONNECT='TRUE';
    'VREFCA':
      PIN_NUMBER='(146,0,0,0)';
      BIDIRECTIONAL='TRUE';
      INPUT_LOAD='(-0.01,0.01)';
      OUTPUT_LOAD='(1.0,-1.0)';
    'VSS'<93>:
      PIN_NUMBER='(0,0,2,0)';
      PINUSE='GROUND';
      NO_LOAD_CHECK='Both';
      NO_IO_CHECK='Both';
      NO_ASSERT_CHECK='TRUE';
      NO_DIR_CHECK='TRUE';
      ALLOW_CONNECT='TRUE';
    'VSS'<92>:
      PIN_NUMBER='(0,0,4,0)';
      PINUSE='GROUND';
      NO_LOAD_CHECK='Both';
      NO_IO_CHECK='Both';
      NO_ASSERT_CHECK='TRUE';
      NO_DIR_CHECK='TRUE';
      ALLOW_CONNECT='TRUE';
    'VSS'<91>:
      PIN_NUMBER='(0,0,6,0)';
      PINUSE='GROUND';
      NO_LOAD_CHECK='Both';
      NO_IO_CHECK='Both';
      NO_ASSERT_CHECK='TRUE';
      NO_DIR_CHECK='TRUE';
      ALLOW_CONNECT='TRUE';
    'VSS'<90>:
      PIN_NUMBER='(0,0,9,0)';
      PINUSE='GROUND';
      NO_LOAD_CHECK='Both';
      NO_IO_CHECK='Both';
      NO_ASSERT_CHECK='TRUE';
      NO_DIR_CHECK='TRUE';
      ALLOW_CONNECT='TRUE';
    'VSS'<89>:
      PIN_NUMBER='(0,0,11,0)';
      PINUSE='GROUND';
      NO_LOAD_CHECK='Both';
      NO_IO_CHECK='Both';
      NO_ASSERT_CHECK='TRUE';
      NO_DIR_CHECK='TRUE';
      ALLOW_CONNECT='TRUE';
    'VSS'<88>:
      PIN_NUMBER='(0,0,13,0)';
      PINUSE='GROUND';
      NO_LOAD_CHECK='Both';
      NO_IO_CHECK='Both';
      NO_ASSERT_CHECK='TRUE';
      NO_DIR_CHECK='TRUE';
      ALLOW_CONNECT='TRUE';
    'VSS'<87>:
      PIN_NUMBER='(0,0,15,0)';
      PINUSE='GROUND';
      NO_LOAD_CHECK='Both';
      NO_IO_CHECK='Both';
      NO_ASSERT_CHECK='TRUE';
      NO_DIR_CHECK='TRUE';
      ALLOW_CONNECT='TRUE';
    'VSS'<86>:
      PIN_NUMBER='(0,0,17,0)';
      PINUSE='GROUND';
      NO_LOAD_CHECK='Both';
      NO_IO_CHECK='Both';
      NO_ASSERT_CHECK='TRUE';
      NO_DIR_CHECK='TRUE';
      ALLOW_CONNECT='TRUE';
    'VSS'<85>:
      PIN_NUMBER='(0,0,20,0)';
      PINUSE='GROUND';
      NO_LOAD_CHECK='Both';
      NO_IO_CHECK='Both';
      NO_ASSERT_CHECK='TRUE';
      NO_DIR_CHECK='TRUE';
      ALLOW_CONNECT='TRUE';
    'VSS'<84>:
      PIN_NUMBER='(0,0,22,0)';
      PINUSE='GROUND';
      NO_LOAD_CHECK='Both';
      NO_IO_CHECK='Both';
      NO_ASSERT_CHECK='TRUE';
      NO_DIR_CHECK='TRUE';
      ALLOW_CONNECT='TRUE';
    'VSS'<83>:
      PIN_NUMBER='(0,0,24,0)';
      PINUSE='GROUND';
      NO_LOAD_CHECK='Both';
      NO_IO_CHECK='Both';
      NO_ASSERT_CHECK='TRUE';
      NO_DIR_CHECK='TRUE';
      ALLOW_CONNECT='TRUE';
    'VSS'<82>:
      PIN_NUMBER='(0,0,26,0)';
      PINUSE='GROUND';
      NO_LOAD_CHECK='Both';
      NO_IO_CHECK='Both';
      NO_ASSERT_CHECK='TRUE';
      NO_DIR_CHECK='TRUE';
      ALLOW_CONNECT='TRUE';
    'VSS'<81>:
      PIN_NUMBER='(0,0,28,0)';
      PINUSE='GROUND';
      NO_LOAD_CHECK='Both';
      NO_IO_CHECK='Both';
      NO_ASSERT_CHECK='TRUE';
      NO_DIR_CHECK='TRUE';
      ALLOW_CONNECT='TRUE';
    'VSS'<80>:
      PIN_NUMBER='(0,0,31,0)';
      PINUSE='GROUND';
      NO_LOAD_CHECK='Both';
      NO_IO_CHECK='Both';
      NO_ASSERT_CHECK='TRUE';
      NO_DIR_CHECK='TRUE';
      ALLOW_CONNECT='TRUE';
    'VSS'<79>:
      PIN_NUMBER='(0,0,33,0)';
      PINUSE='GROUND';
      NO_LOAD_CHECK='Both';
      NO_IO_CHECK='Both';
      NO_ASSERT_CHECK='TRUE';
      NO_DIR_CHECK='TRUE';
      ALLOW_CONNECT='TRUE';
    'VSS'<78>:
      PIN_NUMBER='(0,0,35,0)';
      PINUSE='GROUND';
      NO_LOAD_CHECK='Both';
      NO_IO_CHECK='Both';
      NO_ASSERT_CHECK='TRUE';
      NO_DIR_CHECK='TRUE';
      ALLOW_CONNECT='TRUE';
    'VSS'<77>:
      PIN_NUMBER='(0,0,37,0)';
      PINUSE='GROUND';
      NO_LOAD_CHECK='Both';
      NO_IO_CHECK='Both';
      NO_ASSERT_CHECK='TRUE';
      NO_DIR_CHECK='TRUE';
      ALLOW_CONNECT='TRUE';
    'VSS'<76>:
      PIN_NUMBER='(0,0,39,0)';
      PINUSE='GROUND';
      NO_LOAD_CHECK='Both';
      NO_IO_CHECK='Both';
      NO_ASSERT_CHECK='TRUE';
      NO_DIR_CHECK='TRUE';
      ALLOW_CONNECT='TRUE';
    'VSS'<75>:
      PIN_NUMBER='(0,0,42,0)';
      PINUSE='GROUND';
      NO_LOAD_CHECK='Both';
      NO_IO_CHECK='Both';
      NO_ASSERT_CHECK='TRUE';
      NO_DIR_CHECK='TRUE';
      ALLOW_CONNECT='TRUE';
    'VSS'<74>:
      PIN_NUMBER='(0,0,44,0)';
      PINUSE='GROUND';
      NO_LOAD_CHECK='Both';
      NO_IO_CHECK='Both';
      NO_ASSERT_CHECK='TRUE';
      NO_DIR_CHECK='TRUE';
      ALLOW_CONNECT='TRUE';
    'VSS'<73>:
      PIN_NUMBER='(0,0,46,0)';
      PINUSE='GROUND';
      NO_LOAD_CHECK='Both';
      NO_IO_CHECK='Both';
      NO_ASSERT_CHECK='TRUE';
      NO_DIR_CHECK='TRUE';
      ALLOW_CONNECT='TRUE';
    'VSS'<72>:
      PIN_NUMBER='(0,0,48,0)';
      PINUSE='GROUND';
      NO_LOAD_CHECK='Both';
      NO_IO_CHECK='Both';
      NO_ASSERT_CHECK='TRUE';
      NO_DIR_CHECK='TRUE';
      ALLOW_CONNECT='TRUE';
    'VSS'<71>:
      PIN_NUMBER='(0,0,50,0)';
      PINUSE='GROUND';
      NO_LOAD_CHECK='Both';
      NO_IO_CHECK='Both';
      NO_ASSERT_CHECK='TRUE';
      NO_DIR_CHECK='TRUE';
      ALLOW_CONNECT='TRUE';
    'VSS'<70>:
      PIN_NUMBER='(0,0,53,0)';
      PINUSE='GROUND';
      NO_LOAD_CHECK='Both';
      NO_IO_CHECK='Both';
      NO_ASSERT_CHECK='TRUE';
      NO_DIR_CHECK='TRUE';
      ALLOW_CONNECT='TRUE';
    'VSS'<69>:
      PIN_NUMBER='(0,0,55,0)';
      PINUSE='GROUND';
      NO_LOAD_CHECK='Both';
      NO_IO_CHECK='Both';
      NO_ASSERT_CHECK='TRUE';
      NO_DIR_CHECK='TRUE';
      ALLOW_CONNECT='TRUE';
    'VSS'<68>:
      PIN_NUMBER='(0,0,57,0)';
      PINUSE='GROUND';
      NO_LOAD_CHECK='Both';
      NO_IO_CHECK='Both';
      NO_ASSERT_CHECK='TRUE';
      NO_DIR_CHECK='TRUE';
      ALLOW_CONNECT='TRUE';
    'VSS'<67>:
      PIN_NUMBER='(0,0,94,0)';
      PINUSE='GROUND';
      NO_LOAD_CHECK='Both';
      NO_IO_CHECK='Both';
      NO_ASSERT_CHECK='TRUE';
      NO_DIR_CHECK='TRUE';
      ALLOW_CONNECT='TRUE';
    'VSS'<66>:
      PIN_NUMBER='(0,0,96,0)';
      PINUSE='GROUND';
      NO_LOAD_CHECK='Both';
      NO_IO_CHECK='Both';
      NO_ASSERT_CHECK='TRUE';
      NO_DIR_CHECK='TRUE';
      ALLOW_CONNECT='TRUE';
    'VSS'<65>:
      PIN_NUMBER='(0,0,98,0)';
      PINUSE='GROUND';
      NO_LOAD_CHECK='Both';
      NO_IO_CHECK='Both';
      NO_ASSERT_CHECK='TRUE';
      NO_DIR_CHECK='TRUE';
      ALLOW_CONNECT='TRUE';
    'VSS'<64>:
      PIN_NUMBER='(0,0,101,0)';
      PINUSE='GROUND';
      NO_LOAD_CHECK='Both';
      NO_IO_CHECK='Both';
      NO_ASSERT_CHECK='TRUE';
      NO_DIR_CHECK='TRUE';
      ALLOW_CONNECT='TRUE';
    'VSS'<63>:
      PIN_NUMBER='(0,0,103,0)';
      PINUSE='GROUND';
      NO_LOAD_CHECK='Both';
      NO_IO_CHECK='Both';
      NO_ASSERT_CHECK='TRUE';
      NO_DIR_CHECK='TRUE';
      ALLOW_CONNECT='TRUE';
    'VSS'<62>:
      PIN_NUMBER='(0,0,105,0)';
      PINUSE='GROUND';
      NO_LOAD_CHECK='Both';
      NO_IO_CHECK='Both';
      NO_ASSERT_CHECK='TRUE';
      NO_DIR_CHECK='TRUE';
      ALLOW_CONNECT='TRUE';
    'VSS'<61>:
      PIN_NUMBER='(0,0,107,0)';
      PINUSE='GROUND';
      NO_LOAD_CHECK='Both';
      NO_IO_CHECK='Both';
      NO_ASSERT_CHECK='TRUE';
      NO_DIR_CHECK='TRUE';
      ALLOW_CONNECT='TRUE';
    'VSS'<60>:
      PIN_NUMBER='(0,0,109,0)';
      PINUSE='GROUND';
      NO_LOAD_CHECK='Both';
      NO_IO_CHECK='Both';
      NO_ASSERT_CHECK='TRUE';
      NO_DIR_CHECK='TRUE';
      ALLOW_CONNECT='TRUE';
    'VSS'<59>:
      PIN_NUMBER='(0,0,112,0)';
      PINUSE='GROUND';
      NO_LOAD_CHECK='Both';
      NO_IO_CHECK='Both';
      NO_ASSERT_CHECK='TRUE';
      NO_DIR_CHECK='TRUE';
      ALLOW_CONNECT='TRUE';
    'VSS'<58>:
      PIN_NUMBER='(0,0,114,0)';
      PINUSE='GROUND';
      NO_LOAD_CHECK='Both';
      NO_IO_CHECK='Both';
      NO_ASSERT_CHECK='TRUE';
      NO_DIR_CHECK='TRUE';
      ALLOW_CONNECT='TRUE';
    'VSS'<57>:
      PIN_NUMBER='(0,0,116,0)';
      PINUSE='GROUND';
      NO_LOAD_CHECK='Both';
      NO_IO_CHECK='Both';
      NO_ASSERT_CHECK='TRUE';
      NO_DIR_CHECK='TRUE';
      ALLOW_CONNECT='TRUE';
    'VSS'<56>:
      PIN_NUMBER='(0,0,118,0)';
      PINUSE='GROUND';
      NO_LOAD_CHECK='Both';
      NO_IO_CHECK='Both';
      NO_ASSERT_CHECK='TRUE';
      NO_DIR_CHECK='TRUE';
      ALLOW_CONNECT='TRUE';
    'VSS'<55>:
      PIN_NUMBER='(0,0,120,0)';
      PINUSE='GROUND';
      NO_LOAD_CHECK='Both';
      NO_IO_CHECK='Both';
      NO_ASSERT_CHECK='TRUE';
      NO_DIR_CHECK='TRUE';
      ALLOW_CONNECT='TRUE';
    'VSS'<54>:
      PIN_NUMBER='(0,0,123,0)';
      PINUSE='GROUND';
      NO_LOAD_CHECK='Both';
      NO_IO_CHECK='Both';
      NO_ASSERT_CHECK='TRUE';
      NO_DIR_CHECK='TRUE';
      ALLOW_CONNECT='TRUE';
    'VSS'<53>:
      PIN_NUMBER='(0,0,125,0)';
      PINUSE='GROUND';
      NO_LOAD_CHECK='Both';
      NO_IO_CHECK='Both';
      NO_ASSERT_CHECK='TRUE';
      NO_DIR_CHECK='TRUE';
      ALLOW_CONNECT='TRUE';
    'VSS'<52>:
      PIN_NUMBER='(0,0,127,0)';
      PINUSE='GROUND';
      NO_LOAD_CHECK='Both';
      NO_IO_CHECK='Both';
      NO_ASSERT_CHECK='TRUE';
      NO_DIR_CHECK='TRUE';
      ALLOW_CONNECT='TRUE';
    'VSS'<51>:
      PIN_NUMBER='(0,0,129,0)';
      PINUSE='GROUND';
      NO_LOAD_CHECK='Both';
      NO_IO_CHECK='Both';
      NO_ASSERT_CHECK='TRUE';
      NO_DIR_CHECK='TRUE';
      ALLOW_CONNECT='TRUE';
    'VSS'<50>:
      PIN_NUMBER='(0,0,131,0)';
      PINUSE='GROUND';
      NO_LOAD_CHECK='Both';
      NO_IO_CHECK='Both';
      NO_ASSERT_CHECK='TRUE';
      NO_DIR_CHECK='TRUE';
      ALLOW_CONNECT='TRUE';
    'VSS'<49>:
      PIN_NUMBER='(0,0,134,0)';
      PINUSE='GROUND';
      NO_LOAD_CHECK='Both';
      NO_IO_CHECK='Both';
      NO_ASSERT_CHECK='TRUE';
      NO_DIR_CHECK='TRUE';
      ALLOW_CONNECT='TRUE';
    'VSS'<48>:
      PIN_NUMBER='(0,0,136,0)';
      PINUSE='GROUND';
      NO_LOAD_CHECK='Both';
      NO_IO_CHECK='Both';
      NO_ASSERT_CHECK='TRUE';
      NO_DIR_CHECK='TRUE';
      ALLOW_CONNECT='TRUE';
    'VSS'<47>:
      PIN_NUMBER='(0,0,138,0)';
      PINUSE='GROUND';
      NO_LOAD_CHECK='Both';
      NO_IO_CHECK='Both';
      NO_ASSERT_CHECK='TRUE';
      NO_DIR_CHECK='TRUE';
      ALLOW_CONNECT='TRUE';
    'VSS'<46>:
      PIN_NUMBER='(0,0,147,0)';
      PINUSE='GROUND';
      NO_LOAD_CHECK='Both';
      NO_IO_CHECK='Both';
      NO_ASSERT_CHECK='TRUE';
      NO_DIR_CHECK='TRUE';
      ALLOW_CONNECT='TRUE';
    'VSS'<45>:
      PIN_NUMBER='(0,0,149,0)';
      PINUSE='GROUND';
      NO_LOAD_CHECK='Both';
      NO_IO_CHECK='Both';
      NO_ASSERT_CHECK='TRUE';
      NO_DIR_CHECK='TRUE';
      ALLOW_CONNECT='TRUE';
    'VSS'<44>:
      PIN_NUMBER='(0,0,151,0)';
      PINUSE='GROUND';
      NO_LOAD_CHECK='Both';
      NO_IO_CHECK='Both';
      NO_ASSERT_CHECK='TRUE';
      NO_DIR_CHECK='TRUE';
      ALLOW_CONNECT='TRUE';
    'VSS'<43>:
      PIN_NUMBER='(0,0,154,0)';
      PINUSE='GROUND';
      NO_LOAD_CHECK='Both';
      NO_IO_CHECK='Both';
      NO_ASSERT_CHECK='TRUE';
      NO_DIR_CHECK='TRUE';
      ALLOW_CONNECT='TRUE';
    'VSS'<42>:
      PIN_NUMBER='(0,0,156,0)';
      PINUSE='GROUND';
      NO_LOAD_CHECK='Both';
      NO_IO_CHECK='Both';
      NO_ASSERT_CHECK='TRUE';
      NO_DIR_CHECK='TRUE';
      ALLOW_CONNECT='TRUE';
    'VSS'<41>:
      PIN_NUMBER='(0,0,158,0)';
      PINUSE='GROUND';
      NO_LOAD_CHECK='Both';
      NO_IO_CHECK='Both';
      NO_ASSERT_CHECK='TRUE';
      NO_DIR_CHECK='TRUE';
      ALLOW_CONNECT='TRUE';
    'VSS'<40>:
      PIN_NUMBER='(0,0,160,0)';
      PINUSE='GROUND';
      NO_LOAD_CHECK='Both';
      NO_IO_CHECK='Both';
      NO_ASSERT_CHECK='TRUE';
      NO_DIR_CHECK='TRUE';
      ALLOW_CONNECT='TRUE';
    'VSS'<39>:
      PIN_NUMBER='(0,0,162,0)';
      PINUSE='GROUND';
      NO_LOAD_CHECK='Both';
      NO_IO_CHECK='Both';
      NO_ASSERT_CHECK='TRUE';
      NO_DIR_CHECK='TRUE';
      ALLOW_CONNECT='TRUE';
    'VSS'<38>:
      PIN_NUMBER='(0,0,165,0)';
      PINUSE='GROUND';
      NO_LOAD_CHECK='Both';
      NO_IO_CHECK='Both';
      NO_ASSERT_CHECK='TRUE';
      NO_DIR_CHECK='TRUE';
      ALLOW_CONNECT='TRUE';
    'VSS'<37>:
      PIN_NUMBER='(0,0,167,0)';
      PINUSE='GROUND';
      NO_LOAD_CHECK='Both';
      NO_IO_CHECK='Both';
      NO_ASSERT_CHECK='TRUE';
      NO_DIR_CHECK='TRUE';
      ALLOW_CONNECT='TRUE';
    'VSS'<36>:
      PIN_NUMBER='(0,0,169,0)';
      PINUSE='GROUND';
      NO_LOAD_CHECK='Both';
      NO_IO_CHECK='Both';
      NO_ASSERT_CHECK='TRUE';
      NO_DIR_CHECK='TRUE';
      ALLOW_CONNECT='TRUE';
    'VSS'<35>:
      PIN_NUMBER='(0,0,171,0)';
      PINUSE='GROUND';
      NO_LOAD_CHECK='Both';
      NO_IO_CHECK='Both';
      NO_ASSERT_CHECK='TRUE';
      NO_DIR_CHECK='TRUE';
      ALLOW_CONNECT='TRUE';
    'VSS'<34>:
      PIN_NUMBER='(0,0,173,0)';
      PINUSE='GROUND';
      NO_LOAD_CHECK='Both';
      NO_IO_CHECK='Both';
      NO_ASSERT_CHECK='TRUE';
      NO_DIR_CHECK='TRUE';
      ALLOW_CONNECT='TRUE';
    'VSS'<33>:
      PIN_NUMBER='(0,0,176,0)';
      PINUSE='GROUND';
      NO_LOAD_CHECK='Both';
      NO_IO_CHECK='Both';
      NO_ASSERT_CHECK='TRUE';
      NO_DIR_CHECK='TRUE';
      ALLOW_CONNECT='TRUE';
    'VSS'<32>:
      PIN_NUMBER='(0,0,178,0)';
      PINUSE='GROUND';
      NO_LOAD_CHECK='Both';
      NO_IO_CHECK='Both';
      NO_ASSERT_CHECK='TRUE';
      NO_DIR_CHECK='TRUE';
      ALLOW_CONNECT='TRUE';
    'VSS'<31>:
      PIN_NUMBER='(0,0,180,0)';
      PINUSE='GROUND';
      NO_LOAD_CHECK='Both';
      NO_IO_CHECK='Both';
      NO_ASSERT_CHECK='TRUE';
      NO_DIR_CHECK='TRUE';
      ALLOW_CONNECT='TRUE';
    'VSS'<30>:
      PIN_NUMBER='(0,0,182,0)';
      PINUSE='GROUND';
      NO_LOAD_CHECK='Both';
      NO_IO_CHECK='Both';
      NO_ASSERT_CHECK='TRUE';
      NO_DIR_CHECK='TRUE';
      ALLOW_CONNECT='TRUE';
    'VSS'<29>:
      PIN_NUMBER='(0,0,184,0)';
      PINUSE='GROUND';
      NO_LOAD_CHECK='Both';
      NO_IO_CHECK='Both';
      NO_ASSERT_CHECK='TRUE';
      NO_DIR_CHECK='TRUE';
      ALLOW_CONNECT='TRUE';
    'VSS'<28>:
      PIN_NUMBER='(0,0,187,0)';
      PINUSE='GROUND';
      NO_LOAD_CHECK='Both';
      NO_IO_CHECK='Both';
      NO_ASSERT_CHECK='TRUE';
      NO_DIR_CHECK='TRUE';
      ALLOW_CONNECT='TRUE';
    'VSS'<27>:
      PIN_NUMBER='(0,0,189,0)';
      PINUSE='GROUND';
      NO_LOAD_CHECK='Both';
      NO_IO_CHECK='Both';
      NO_ASSERT_CHECK='TRUE';
      NO_DIR_CHECK='TRUE';
      ALLOW_CONNECT='TRUE';
    'VSS'<26>:
      PIN_NUMBER='(0,0,191,0)';
      PINUSE='GROUND';
      NO_LOAD_CHECK='Both';
      NO_IO_CHECK='Both';
      NO_ASSERT_CHECK='TRUE';
      NO_DIR_CHECK='TRUE';
      ALLOW_CONNECT='TRUE';
    'VSS'<25>:
      PIN_NUMBER='(0,0,193,0)';
      PINUSE='GROUND';
      NO_LOAD_CHECK='Both';
      NO_IO_CHECK='Both';
      NO_ASSERT_CHECK='TRUE';
      NO_DIR_CHECK='TRUE';
      ALLOW_CONNECT='TRUE';
    'VSS'<24>:
      PIN_NUMBER='(0,0,195,0)';
      PINUSE='GROUND';
      NO_LOAD_CHECK='Both';
      NO_IO_CHECK='Both';
      NO_ASSERT_CHECK='TRUE';
      NO_DIR_CHECK='TRUE';
      ALLOW_CONNECT='TRUE';
    'VSS'<23>:
      PIN_NUMBER='(0,0,198,0)';
      PINUSE='GROUND';
      NO_LOAD_CHECK='Both';
      NO_IO_CHECK='Both';
      NO_ASSERT_CHECK='TRUE';
      NO_DIR_CHECK='TRUE';
      ALLOW_CONNECT='TRUE';
    'VSS'<22>:
      PIN_NUMBER='(0,0,200,0)';
      PINUSE='GROUND';
      NO_LOAD_CHECK='Both';
      NO_IO_CHECK='Both';
      NO_ASSERT_CHECK='TRUE';
      NO_DIR_CHECK='TRUE';
      ALLOW_CONNECT='TRUE';
    'VSS'<21>:
      PIN_NUMBER='(0,0,202,0)';
      PINUSE='GROUND';
      NO_LOAD_CHECK='Both';
      NO_IO_CHECK='Both';
      NO_ASSERT_CHECK='TRUE';
      NO_DIR_CHECK='TRUE';
      ALLOW_CONNECT='TRUE';
    'VSS'<20>:
      PIN_NUMBER='(0,0,239,0)';
      PINUSE='GROUND';
      NO_LOAD_CHECK='Both';
      NO_IO_CHECK='Both';
      NO_ASSERT_CHECK='TRUE';
      NO_DIR_CHECK='TRUE';
      ALLOW_CONNECT='TRUE';
    'VSS'<19>:
      PIN_NUMBER='(0,0,241,0)';
      PINUSE='GROUND';
      NO_LOAD_CHECK='Both';
      NO_IO_CHECK='Both';
      NO_ASSERT_CHECK='TRUE';
      NO_DIR_CHECK='TRUE';
      ALLOW_CONNECT='TRUE';
    'VSS'<18>:
      PIN_NUMBER='(0,0,243,0)';
      PINUSE='GROUND';
      NO_LOAD_CHECK='Both';
      NO_IO_CHECK='Both';
      NO_ASSERT_CHECK='TRUE';
      NO_DIR_CHECK='TRUE';
      ALLOW_CONNECT='TRUE';
    'VSS'<17>:
      PIN_NUMBER='(0,0,246,0)';
      PINUSE='GROUND';
      NO_LOAD_CHECK='Both';
      NO_IO_CHECK='Both';
      NO_ASSERT_CHECK='TRUE';
      NO_DIR_CHECK='TRUE';
      ALLOW_CONNECT='TRUE';
    'VSS'<16>:
      PIN_NUMBER='(0,0,248,0)';
      PINUSE='GROUND';
      NO_LOAD_CHECK='Both';
      NO_IO_CHECK='Both';
      NO_ASSERT_CHECK='TRUE';
      NO_DIR_CHECK='TRUE';
      ALLOW_CONNECT='TRUE';
    'VSS'<15>:
      PIN_NUMBER='(0,0,250,0)';
      PINUSE='GROUND';
      NO_LOAD_CHECK='Both';
      NO_IO_CHECK='Both';
      NO_ASSERT_CHECK='TRUE';
      NO_DIR_CHECK='TRUE';
      ALLOW_CONNECT='TRUE';
    'VSS'<14>:
      PIN_NUMBER='(0,0,252,0)';
      PINUSE='GROUND';
      NO_LOAD_CHECK='Both';
      NO_IO_CHECK='Both';
      NO_ASSERT_CHECK='TRUE';
      NO_DIR_CHECK='TRUE';
      ALLOW_CONNECT='TRUE';
    'VSS'<13>:
      PIN_NUMBER='(0,0,254,0)';
      PINUSE='GROUND';
      NO_LOAD_CHECK='Both';
      NO_IO_CHECK='Both';
      NO_ASSERT_CHECK='TRUE';
      NO_DIR_CHECK='TRUE';
      ALLOW_CONNECT='TRUE';
    'VSS'<12>:
      PIN_NUMBER='(0,0,257,0)';
      PINUSE='GROUND';
      NO_LOAD_CHECK='Both';
      NO_IO_CHECK='Both';
      NO_ASSERT_CHECK='TRUE';
      NO_DIR_CHECK='TRUE';
      ALLOW_CONNECT='TRUE';
    'VSS'<11>:
      PIN_NUMBER='(0,0,259,0)';
      PINUSE='GROUND';
      NO_LOAD_CHECK='Both';
      NO_IO_CHECK='Both';
      NO_ASSERT_CHECK='TRUE';
      NO_DIR_CHECK='TRUE';
      ALLOW_CONNECT='TRUE';
    'VSS'<10>:
      PIN_NUMBER='(0,0,261,0)';
      PINUSE='GROUND';
      NO_LOAD_CHECK='Both';
      NO_IO_CHECK='Both';
      NO_ASSERT_CHECK='TRUE';
      NO_DIR_CHECK='TRUE';
      ALLOW_CONNECT='TRUE';
    'VSS'<9>:
      PIN_NUMBER='(0,0,263,0)';
      PINUSE='GROUND';
      NO_LOAD_CHECK='Both';
      NO_IO_CHECK='Both';
      NO_ASSERT_CHECK='TRUE';
      NO_DIR_CHECK='TRUE';
      ALLOW_CONNECT='TRUE';
    'VSS'<8>:
      PIN_NUMBER='(0,0,265,0)';
      PINUSE='GROUND';
      NO_LOAD_CHECK='Both';
      NO_IO_CHECK='Both';
      NO_ASSERT_CHECK='TRUE';
      NO_DIR_CHECK='TRUE';
      ALLOW_CONNECT='TRUE';
    'VSS'<7>:
      PIN_NUMBER='(0,0,268,0)';
      PINUSE='GROUND';
      NO_LOAD_CHECK='Both';
      NO_IO_CHECK='Both';
      NO_ASSERT_CHECK='TRUE';
      NO_DIR_CHECK='TRUE';
      ALLOW_CONNECT='TRUE';
    'VSS'<6>:
      PIN_NUMBER='(0,0,270,0)';
      PINUSE='GROUND';
      NO_LOAD_CHECK='Both';
      NO_IO_CHECK='Both';
      NO_ASSERT_CHECK='TRUE';
      NO_DIR_CHECK='TRUE';
      ALLOW_CONNECT='TRUE';
    'VSS'<5>:
      PIN_NUMBER='(0,0,272,0)';
      PINUSE='GROUND';
      NO_LOAD_CHECK='Both';
      NO_IO_CHECK='Both';
      NO_ASSERT_CHECK='TRUE';
      NO_DIR_CHECK='TRUE';
      ALLOW_CONNECT='TRUE';
    'VSS'<4>:
      PIN_NUMBER='(0,0,274,0)';
      PINUSE='GROUND';
      NO_LOAD_CHECK='Both';
      NO_IO_CHECK='Both';
      NO_ASSERT_CHECK='TRUE';
      NO_DIR_CHECK='TRUE';
      ALLOW_CONNECT='TRUE';
    'VSS'<3>:
      PIN_NUMBER='(0,0,276,0)';
      PINUSE='GROUND';
      NO_LOAD_CHECK='Both';
      NO_IO_CHECK='Both';
      NO_ASSERT_CHECK='TRUE';
      NO_DIR_CHECK='TRUE';
      ALLOW_CONNECT='TRUE';
    'VSS'<2>:
      PIN_NUMBER='(0,0,279,0)';
      PINUSE='GROUND';
      NO_LOAD_CHECK='Both';
      NO_IO_CHECK='Both';
      NO_ASSERT_CHECK='TRUE';
      NO_DIR_CHECK='TRUE';
      ALLOW_CONNECT='TRUE';
    'VSS'<1>:
      PIN_NUMBER='(0,0,281,0)';
      PINUSE='GROUND';
      NO_LOAD_CHECK='Both';
      NO_IO_CHECK='Both';
      NO_ASSERT_CHECK='TRUE';
      NO_DIR_CHECK='TRUE';
      ALLOW_CONNECT='TRUE';
    'VSS'<0>:
      PIN_NUMBER='(0,0,283,0)';
      PINUSE='GROUND';
      NO_LOAD_CHECK='Both';
      NO_IO_CHECK='Both';
      NO_ASSERT_CHECK='TRUE';
      NO_DIR_CHECK='TRUE';
      ALLOW_CONNECT='TRUE';
    'VTT'<1>:
      PIN_NUMBER='(0,0,0,77)';
      PINUSE='POWER';
      NO_LOAD_CHECK='Both';
      NO_IO_CHECK='Both';
      NO_ASSERT_CHECK='TRUE';
      NO_DIR_CHECK='TRUE';
      ALLOW_CONNECT='TRUE';
    'VTT'<0>:
      PIN_NUMBER='(0,0,0,221)';
      PINUSE='POWER';
      NO_LOAD_CHECK='Both';
      NO_IO_CHECK='Both';
      NO_ASSERT_CHECK='TRUE';
      NO_DIR_CHECK='TRUE';
      ALLOW_CONNECT='TRUE';
  end_pin;
  body
    PART_NAME='SCONN288_H44441003';
    PHYS_DES_PREFIX='J';
  end_body;
end_primitive;

END.
